# T6G (Grand Teton) — schematic netlist excerpt (pin names and nets, part order shuffled) for the footprints in the layout excerpt that follows; sources: Cadence DE-HDL packaged netlist, KiCad conversion of 04192023_DAF0TMB3IC0_F0TG_MB_C_brd_V02_OCP.brd

L14  Q_INDUCTOR  100NH/16A IND  pkg SMLF  page 290 : \1\ = P0V9_CPU0_RT_2D ; \2\ = P0V9_CPU0_RT1_2A
D84  Q_LED  IC  pkg SMLF  page 256 : A = LED_PWRGD_PVDD11_S3_P1_R ; C = LED_PWRGD_PVDD11_S3_P1_D
R6111  Q_RES  0 5% CHIP  pkg 0402LF  page 172 : A = JTAG_TDO_R1 ; B = JTAG_TDO

(kicad_pcb
	(version 20260206)
	(generator "pcbnew")
	(generator_version "10.0")
	(general
		(thickness 1.6)
		(legacy_teardrops no)
	)
	(paper "A4")
	(title_block
		(title "04192023_DAF0TMB3IC0_F0TG_MB_C_brd_V02_OCP.brd")
		(comment 1 "Grand Teton / footprints 1490-1492 of 8354")
	)
	(layers
		(0 "F.Cu" signal "TOP")
		(4 "In1.Cu" signal "GND")
		(6 "In2.Cu" signal "IN1")
		(8 "In3.Cu" signal "GND1")
		(10 "In4.Cu" signal "IN2")
		(12 "In5.Cu" signal "GND2")
		(14 "In6.Cu" signal "IN3")
		(16 "In7.Cu" signal "GND3")
		(18 "In8.Cu" signal "VCC")
		(20 "In9.Cu" signal "VCC1")
		(22 "In10.Cu" signal "GND4")
		(24 "In11.Cu" signal "IN4")
		(26 "In12.Cu" signal "GND5")
		(28 "In13.Cu" signal "IN5")
		(30 "In14.Cu" signal "GND6")
		(32 "In15.Cu" signal "IN6")
		(34 "In16.Cu" signal "GND7")
		(2 "B.Cu" signal "BOTTOM")
		(9 "F.Adhes" user "F.Adhesive")
		(11 "B.Adhes" user "B.Adhesive")
		(13 "F.Paste" user "Package Geometry/Pastemask Top")
		(15 "B.Paste" user "Package Geometry/Pastemask Bottom")
		(5 "F.SilkS" user "Ref Des/Silkscreen Top")
		(7 "B.SilkS" user "Ref Des/Silkscreen Bottom")
		(1 "F.Mask" user "Board Geometry/Soldermask Top")
		(3 "B.Mask" user "Board Geometry/Soldermask Bottom")
		(17 "Dwgs.User" user "User.Drawings")
		(19 "Cmts.User" user "User.Comments")
		(21 "Eco1.User" user "User.Eco1")
		(23 "Eco2.User" user "User.Eco2")
		(25 "Edge.Cuts" user "Board Geometry/Outline")
		(27 "Margin" user)
		(31 "F.CrtYd" user "Package Geometry/Place Bound Top")
		(29 "B.CrtYd" user "Package Geometry/Place Bound Bottom")
		(35 "F.Fab" user "Ref Des/Assembly Top")
		(33 "B.Fab" user "Ref Des/Assembly Bottom")
	)
	(footprint ""
		(layer "F.Cu")
		(at 344.955876 -70.098412 90)
		(property "Reference" "D84"
			(at -3.934714 -0.691642 90)
			(unlocked yes)
			(layer "F.SilkS")
			(effects
				(font
					(size 0.7874 0.5842)
					(thickness 0.1524)
				)
				(justify left)
			)
		)
		(property "Value" ""
			(at 0 0 90)
			(layer "F.Fab")
			(effects
				(font
					(size 1.27 1.27)
				)
			)
		)
		(duplicate_pad_numbers_are_jumpers no)
		(fp_line
			(start 1.16078 -0.4826)
			(end 1.16078 0.4826)
			(stroke
				(width 0.1524)
				(type default)
			)
			(layer "F.SilkS")
		)
		(fp_line
			(start 1.03378 -0.4826)
			(end 1.03378 0.4826)
			(stroke
				(width 0.1524)
				(type default)
			)
			(layer "F.SilkS")
		)
		(fp_line
			(start 0.90678 -0.4826)
			(end 0.90678 0.4826)
			(stroke
				(width 0.1524)
				(type default)
			)
			(layer "F.SilkS")
		)
		(fp_line
			(start -0.64008 -0.4826)
			(end 1.16078 -0.4826)
			(stroke
				(width 0.1524)
				(type default)
			)
			(layer "F.SilkS")
		)
		(fp_line
			(start -0.79248 -0.4826)
			(end 1.03378 -0.4826)
			(stroke
				(width 0.1524)
				(type default)
			)
			(layer "F.SilkS")
		)
		(fp_line
			(start -0.89408 -0.4826)
			(end 0.90678 -0.4826)
			(stroke
				(width 0.1524)
				(type default)
			)
			(layer "F.SilkS")
		)
		(fp_line
			(start 1.16078 0.4826)
			(end -0.64008 0.4826)
			(stroke
				(width 0.1524)
				(type default)
			)
			(layer "F.SilkS")
		)
		(fp_line
			(start 1.03378 0.4826)
			(end -0.79248 0.4826)
			(stroke
				(width 0.1524)
				(type default)
			)
			(layer "F.SilkS")
		)
		(fp_line
			(start 0.90678 0.4826)
			(end -0.90678 0.4826)
			(stroke
				(width 0.1524)
				(type default)
			)
			(layer "F.SilkS")
		)
		(fp_line
			(start -0.90678 0.4826)
			(end -0.90678 -0.4699)
			(stroke
				(width 0.1524)
				(type default)
			)
			(layer "F.SilkS")
		)
		(fp_line
			(start 0.499872 -0.249936)
			(end 0.499872 0.249936)
			(stroke
				(width 0.1)
				(type default)
			)
			(layer "F.Fab")
		)
		(fp_line
			(start -0.499872 -0.249936)
			(end 0.499872 -0.249936)
			(stroke
				(width 0.1)
				(type default)
			)
			(layer "F.Fab")
		)
		(fp_line
			(start 0.499872 0.249936)
			(end -0.499872 0.249936)
			(stroke
				(width 0.1)
				(type default)
			)
			(layer "F.Fab")
		)
		(fp_line
			(start -0.499872 0.249936)
			(end -0.499872 -0.249936)
			(stroke
				(width 0.1)
				(type default)
			)
			(layer "F.Fab")
		)
		(pad "A" smd rect
			(at -0.47498 0 90)
			(size 0.6096 0.7112)
			(layers "F.Cu" "F.Mask" "F.Paste")
			(net "LED_PWRGD_PVDD11_S3_P1_R")
		)
		(pad "C" smd rect
			(at 0.47498 0 90)
			(size 0.6096 0.7112)
			(layers "F.Cu" "F.Mask" "F.Paste")
			(net "LED_PWRGD_PVDD11_S3_P1_D")
		)
	)
	(footprint ""
		(layer "F.Cu")
		(at 125.512576 -55.175658 90)
		(property "Reference" "R6111"
			(at 0 0 90)
			(layer "F.SilkS")
			(hide yes)
			(effects
				(font
					(size 1.27 1.27)
				)
			)
		)
		(property "Value" ""
			(at 0 0 90)
			(layer "F.Fab")
			(effects
				(font
					(size 1.27 1.27)
				)
			)
		)
		(duplicate_pad_numbers_are_jumpers no)
		(fp_line
			(start 0.7874 -0.4064)
			(end 0.7874 0.4064)
			(stroke
				(width 0.1524)
				(type default)
			)
			(layer "F.SilkS")
		)
		(fp_line
			(start -0.7874 -0.4064)
			(end 0.7874 -0.4064)
			(stroke
				(width 0.1524)
				(type default)
			)
			(layer "F.SilkS")
		)
		(fp_line
			(start 0.7874 0.4064)
			(end -0.7874 0.4064)
			(stroke
				(width 0.1524)
				(type default)
			)
			(layer "F.SilkS")
		)
		(fp_line
			(start -0.7874 0.4064)
			(end -0.7874 -0.4064)
			(stroke
				(width 0.1524)
				(type default)
			)
			(layer "F.SilkS")
		)
		(fp_line
			(start -0.12065 -0.305054)
			(end -0.12065 -0.2794)
			(stroke
				(width 0.1)
				(type default)
			)
			(layer "F.Fab")
		)
		(fp_line
			(start -0.67945 -0.305054)
			(end -0.12065 -0.305054)
			(stroke
				(width 0.1)
				(type default)
			)
			(layer "F.Fab")
		)
		(fp_line
			(start 0.67945 -0.3048)
			(end 0.67945 0.3048)
			(stroke
				(width 0.1)
				(type default)
			)
			(layer "F.Fab")
		)
		(fp_line
			(start 0.12065 -0.3048)
			(end 0.67945 -0.3048)
			(stroke
				(width 0.1)
				(type default)
			)
			(layer "F.Fab")
		)
		(fp_line
			(start 0.12065 -0.2794)
			(end 0.12065 -0.3048)
			(stroke
				(width 0.1)
				(type default)
			)
			(layer "F.Fab")
		)
		(fp_line
			(start -0.12065 -0.2794)
			(end 0.12065 -0.2794)
			(stroke
				(width 0.1)
				(type default)
			)
			(layer "F.Fab")
		)
		(fp_line
			(start 0.120396 0.2794)
			(end -0.12065 0.2794)
			(stroke
				(width 0.1)
				(type default)
			)
			(layer "F.Fab")
		)
		(fp_line
			(start -0.12065 0.2794)
			(end -0.12065 0.3048)
			(stroke
				(width 0.1)
				(type default)
			)
			(layer "F.Fab")
		)
		(fp_line
			(start 0.67945 0.3048)
			(end 0.120396 0.3048)
			(stroke
				(width 0.1)
				(type default)
			)
			(layer "F.Fab")
		)
		(fp_line
			(start 0.120396 0.3048)
			(end 0.120396 0.2794)
			(stroke
				(width 0.1)
				(type default)
			)
			(layer "F.Fab")
		)
		(fp_line
			(start -0.12065 0.3048)
			(end -0.67945 0.3048)
			(stroke
				(width 0.1)
				(type default)
			)
			(layer "F.Fab")
		)
		(fp_line
			(start -0.67945 0.3048)
			(end -0.67945 -0.305054)
			(stroke
				(width 0.1)
				(type default)
			)
			(layer "F.Fab")
		)
		(pad "1" smd circle
			(at -0.40005 0 90)
			(size 0 0)
			(layers "F.Cu" "F.Mask" "F.Paste")
			(net "JTAG_TDO_R1")
		)
		(pad "2" smd circle
			(at 0.40005 0 90)
			(size 0 0)
			(layers "F.Cu" "F.Mask" "F.Paste")
			(net "JTAG_TDO")
		)
	)
	(footprint ""
		(layer "F.Cu")
		(at 329.150472 -400.903694)
		(property "Reference" "L14"
			(at -2.3876 -2.969768 0)
			(unlocked yes)
			(layer "F.SilkS")
			(effects
				(font
					(size 0.7874 0.5842)
					(thickness 0.1524)
				)
				(justify left)
			)
		)
		(property "Value" ""
			(at 0 0 0)
			(layer "F.Fab")
			(effects
				(font
					(size 1.27 1.27)
				)
			)
		)
		(duplicate_pad_numbers_are_jumpers no)
		(fp_line
			(start -2.249932 -2.249932)
			(end 2.249932 -2.249932)
			(stroke
				(width 0.1524)
				(type default)
			)
			(layer "F.SilkS")
		)
		(fp_line
			(start -2.249932 -1.3843)
			(end -2.249932 -2.249932)
			(stroke
				(width 0.1524)
				(type default)
			)
			(layer "F.SilkS")
		)
		(fp_line
			(start -2.249932 2.249932)
			(end -2.249932 1.3843)
			(stroke
				(width 0.1524)
				(type default)
			)
			(layer "F.SilkS")
		)
		(fp_line
			(start 2.249932 -2.249932)
			(end 2.249932 -1.3843)
			(stroke
				(width 0.1524)
				(type default)
			)
			(layer "F.SilkS")
		)
		(fp_line
			(start 2.249932 1.3843)
			(end 2.249932 2.249932)
			(stroke
				(width 0.1524)
				(type default)
			)
			(layer "F.SilkS")
		)
		(fp_line
			(start 2.249932 2.249932)
			(end -2.249932 2.249932)
			(stroke
				(width 0.1524)
				(type default)
			)
			(layer "F.SilkS")
		)
		(fp_line
			(start -2.249932 -2.249932)
			(end 2.249932 -2.249932)
			(stroke
				(width 0.1)
				(type default)
			)
			(layer "F.Fab")
		)
		(fp_line
			(start -2.249932 2.249932)
			(end -2.249932 -2.249932)
			(stroke
				(width 0.1)
				(type default)
			)
			(layer "F.Fab")
		)
		(fp_line
			(start 2.249932 -2.249932)
			(end 2.249932 2.249932)
			(stroke
				(width 0.1)
				(type default)
			)
			(layer "F.Fab")
		)
		(fp_line
			(start 2.249932 2.249932)
			(end -2.249932 2.249932)
			(stroke
				(width 0.1)
				(type default)
			)
			(layer "F.Fab")
		)
		(pad "1" smd rect
			(at -1.82499 0)
			(size 1.0668 2.5146)
			(layers "F.Cu" "F.Mask" "F.Paste")
			(net "P0V9_CPU0_RT_2D")
		)
		(pad "2" smd rect
			(at 1.82499 0)
			(size 1.0668 2.5146)
			(layers "F.Cu" "F.Mask" "F.Paste")
			(net "P0V9_CPU0_RT1_2A")
		)
	)
)
